# T6G (Grand Teton) — schematic netlist excerpt (pin names and nets, part order shuffled) for the footprints in the layout excerpt that follows; sources: Cadence DE-HDL packaged netlist, KiCad conversion of 04192023_DAF0TMB3IC0_F0TG_MB_C_brd_V02_OCP.brd

R267  Q_RES  33 5% CHIP  pkg 0402LF  page 82 : A = CPU1_SA1 ; B = FM_CPU1_SA1
C159  Q_CAP  10UF 25V 10% X6S  pkg C0805  page 93 : A = P12V_MEM_CPU0 ; B = GND
R3096  Q_RES  130 1% CHIP  pkg 0402LF  page 256 : A = LED_PWRGD_PVDDCR_CPU1_P1_R ; B = P3V3_AUX

(kicad_pcb
	(version 20260206)
	(generator "pcbnew")
	(generator_version "10.0")
	(general
		(thickness 1.6)
		(legacy_teardrops no)
	)
	(paper "A4")
	(title_block
		(title "04192023_DAF0TMB3IC0_F0TG_MB_C_brd_V02_OCP.brd")
		(comment 1 "Grand Teton / footprints 7977-7979 of 8354")
	)
	(layers
		(0 "F.Cu" signal "TOP")
		(4 "In1.Cu" signal "GND")
		(6 "In2.Cu" signal "IN1")
		(8 "In3.Cu" signal "GND1")
		(10 "In4.Cu" signal "IN2")
		(12 "In5.Cu" signal "GND2")
		(14 "In6.Cu" signal "IN3")
		(16 "In7.Cu" signal "GND3")
		(18 "In8.Cu" signal "VCC")
		(20 "In9.Cu" signal "VCC1")
		(22 "In10.Cu" signal "GND4")
		(24 "In11.Cu" signal "IN4")
		(26 "In12.Cu" signal "GND5")
		(28 "In13.Cu" signal "IN5")
		(30 "In14.Cu" signal "GND6")
		(32 "In15.Cu" signal "IN6")
		(34 "In16.Cu" signal "GND7")
		(2 "B.Cu" signal "BOTTOM")
		(9 "F.Adhes" user "F.Adhesive")
		(11 "B.Adhes" user "B.Adhesive")
		(13 "F.Paste" user "Package Geometry/Pastemask Top")
		(15 "B.Paste" user "Package Geometry/Pastemask Bottom")
		(5 "F.SilkS" user "Ref Des/Silkscreen Top")
		(7 "B.SilkS" user "Ref Des/Silkscreen Bottom")
		(1 "F.Mask" user "Board Geometry/Soldermask Top")
		(3 "B.Mask" user "Board Geometry/Soldermask Bottom")
		(17 "Dwgs.User" user "User.Drawings")
		(19 "Cmts.User" user "User.Comments")
		(21 "Eco1.User" user "User.Eco1")
		(23 "Eco2.User" user "User.Eco2")
		(25 "Edge.Cuts" user "Board Geometry/Outline")
		(27 "Margin" user)
		(31 "F.CrtYd" user "Package Geometry/Place Bound Top")
		(29 "B.CrtYd" user "Package Geometry/Place Bound Bottom")
		(35 "F.Fab" user "Ref Des/Assembly Top")
		(33 "B.Fab" user "Ref Des/Assembly Bottom")
	)
	(footprint ""
		(layer "B.Cu")
		(at 340.891876 -66.708782 90)
		(property "Reference" "R3096"
			(at 0 0 90)
			(layer "B.SilkS")
			(hide yes)
			(effects
				(font
					(size 1.27 1.27)
				)
				(justify mirror)
			)
		)
		(property "Value" ""
			(at 0 0 90)
			(layer "B.Fab")
			(effects
				(font
					(size 1.27 1.27)
				)
				(justify mirror)
			)
		)
		(duplicate_pad_numbers_are_jumpers no)
		(fp_line
			(start 0.7874 -0.4064)
			(end -0.7874 -0.4064)
			(stroke
				(width 0.1524)
				(type default)
			)
			(layer "B.SilkS")
		)
		(fp_line
			(start -0.7874 -0.4064)
			(end -0.7874 0.4064)
			(stroke
				(width 0.1524)
				(type default)
			)
			(layer "B.SilkS")
		)
		(fp_line
			(start 0.7874 0.4064)
			(end 0.7874 -0.4064)
			(stroke
				(width 0.1524)
				(type default)
			)
			(layer "B.SilkS")
		)
		(fp_line
			(start -0.7874 0.4064)
			(end 0.7874 0.4064)
			(stroke
				(width 0.1524)
				(type default)
			)
			(layer "B.SilkS")
		)
		(fp_line
			(start 0.67945 -0.305054)
			(end 0.12065 -0.305054)
			(stroke
				(width 0.1)
				(type default)
			)
			(layer "B.Fab")
		)
		(fp_line
			(start 0.12065 -0.305054)
			(end 0.12065 -0.2794)
			(stroke
				(width 0.1)
				(type default)
			)
			(layer "B.Fab")
		)
		(fp_line
			(start -0.12065 -0.3048)
			(end -0.67945 -0.3048)
			(stroke
				(width 0.1)
				(type default)
			)
			(layer "B.Fab")
		)
		(fp_line
			(start -0.67945 -0.3048)
			(end -0.67945 0.3048)
			(stroke
				(width 0.1)
				(type default)
			)
			(layer "B.Fab")
		)
		(fp_line
			(start 0.12065 -0.2794)
			(end -0.12065 -0.2794)
			(stroke
				(width 0.1)
				(type default)
			)
			(layer "B.Fab")
		)
		(fp_line
			(start -0.12065 -0.2794)
			(end -0.12065 -0.3048)
			(stroke
				(width 0.1)
				(type default)
			)
			(layer "B.Fab")
		)
		(fp_line
			(start 0.12065 0.2794)
			(end 0.12065 0.3048)
			(stroke
				(width 0.1)
				(type default)
			)
			(layer "B.Fab")
		)
		(fp_line
			(start -0.120396 0.2794)
			(end 0.12065 0.2794)
			(stroke
				(width 0.1)
				(type default)
			)
			(layer "B.Fab")
		)
		(fp_line
			(start 0.67945 0.3048)
			(end 0.67945 -0.305054)
			(stroke
				(width 0.1)
				(type default)
			)
			(layer "B.Fab")
		)
		(fp_line
			(start 0.12065 0.3048)
			(end 0.67945 0.3048)
			(stroke
				(width 0.1)
				(type default)
			)
			(layer "B.Fab")
		)
		(fp_line
			(start -0.120396 0.3048)
			(end -0.120396 0.2794)
			(stroke
				(width 0.1)
				(type default)
			)
			(layer "B.Fab")
		)
		(fp_line
			(start -0.67945 0.3048)
			(end -0.120396 0.3048)
			(stroke
				(width 0.1)
				(type default)
			)
			(layer "B.Fab")
		)
		(pad "1" smd circle
			(at 0.40005 0 270)
			(size 0 0)
			(layers "B.Cu" "B.Mask" "B.Paste")
			(net "LED_PWRGD_PVDDCR_CPU1_P1_R")
		)
		(pad "2" smd circle
			(at -0.40005 0 270)
			(size 0 0)
			(layers "B.Cu" "B.Mask" "B.Paste")
			(net "P3V3_AUX")
		)
	)
	(footprint ""
		(layer "B.Cu")
		(at 194.945 -100.294948 -90)
		(property "Reference" "R267"
			(at 0 0 90)
			(layer "B.SilkS")
			(hide yes)
			(effects
				(font
					(size 1.27 1.27)
				)
				(justify mirror)
			)
		)
		(property "Value" ""
			(at 0 0 90)
			(layer "B.Fab")
			(effects
				(font
					(size 1.27 1.27)
				)
				(justify mirror)
			)
		)
		(duplicate_pad_numbers_are_jumpers no)
		(fp_line
			(start -0.7874 0.4064)
			(end 0.7874 0.4064)
			(stroke
				(width 0.1524)
				(type default)
			)
			(layer "B.SilkS")
		)
		(fp_line
			(start 0.7874 0.4064)
			(end 0.7874 -0.4064)
			(stroke
				(width 0.1524)
				(type default)
			)
			(layer "B.SilkS")
		)
		(fp_line
			(start -0.7874 -0.4064)
			(end -0.7874 0.4064)
			(stroke
				(width 0.1524)
				(type default)
			)
			(layer "B.SilkS")
		)
		(fp_line
			(start 0.7874 -0.4064)
			(end -0.7874 -0.4064)
			(stroke
				(width 0.1524)
				(type default)
			)
			(layer "B.SilkS")
		)
		(fp_line
			(start -0.67945 0.3048)
			(end -0.120396 0.3048)
			(stroke
				(width 0.1)
				(type default)
			)
			(layer "B.Fab")
		)
		(fp_line
			(start -0.120396 0.3048)
			(end -0.120396 0.2794)
			(stroke
				(width 0.1)
				(type default)
			)
			(layer "B.Fab")
		)
		(fp_line
			(start 0.12065 0.3048)
			(end 0.67945 0.3048)
			(stroke
				(width 0.1)
				(type default)
			)
			(layer "B.Fab")
		)
		(fp_line
			(start 0.67945 0.3048)
			(end 0.67945 -0.305054)
			(stroke
				(width 0.1)
				(type default)
			)
			(layer "B.Fab")
		)
		(fp_line
			(start -0.120396 0.2794)
			(end 0.12065 0.2794)
			(stroke
				(width 0.1)
				(type default)
			)
			(layer "B.Fab")
		)
		(fp_line
			(start 0.12065 0.2794)
			(end 0.12065 0.3048)
			(stroke
				(width 0.1)
				(type default)
			)
			(layer "B.Fab")
		)
		(fp_line
			(start -0.12065 -0.2794)
			(end -0.12065 -0.3048)
			(stroke
				(width 0.1)
				(type default)
			)
			(layer "B.Fab")
		)
		(fp_line
			(start 0.12065 -0.2794)
			(end -0.12065 -0.2794)
			(stroke
				(width 0.1)
				(type default)
			)
			(layer "B.Fab")
		)
		(fp_line
			(start -0.67945 -0.3048)
			(end -0.67945 0.3048)
			(stroke
				(width 0.1)
				(type default)
			)
			(layer "B.Fab")
		)
		(fp_line
			(start -0.12065 -0.3048)
			(end -0.67945 -0.3048)
			(stroke
				(width 0.1)
				(type default)
			)
			(layer "B.Fab")
		)
		(fp_line
			(start 0.12065 -0.305054)
			(end 0.12065 -0.2794)
			(stroke
				(width 0.1)
				(type default)
			)
			(layer "B.Fab")
		)
		(fp_line
			(start 0.67945 -0.305054)
			(end 0.12065 -0.305054)
			(stroke
				(width 0.1)
				(type default)
			)
			(layer "B.Fab")
		)
		(pad "1" smd circle
			(at 0.40005 0 90)
			(size 0 0)
			(layers "B.Cu" "B.Mask" "B.Paste")
			(net "CPU1_SA1")
		)
		(pad "2" smd circle
			(at -0.40005 0 90)
			(size 0 0)
			(layers "B.Cu" "B.Mask" "B.Paste")
			(net "FM_CPU1_SA1")
		)
	)
	(footprint ""
		(layer "B.Cu")
		(at 424.012106 -192.660016)
		(property "Reference" "C159"
			(at 0 0 0)
			(layer "B.SilkS")
			(hide yes)
			(effects
				(font
					(size 1.27 1.27)
				)
				(justify mirror)
			)
		)
		(property "Value" ""
			(at 0 0 0)
			(layer "B.Fab")
			(effects
				(font
					(size 1.27 1.27)
				)
				(justify mirror)
			)
		)
		(duplicate_pad_numbers_are_jumpers no)
		(fp_line
			(start -1.524 -0.762)
			(end -1.524 0.762)
			(stroke
				(width 0.1524)
				(type default)
			)
			(layer "B.SilkS")
		)
		(fp_line
			(start -1.524 0.762)
			(end 1.524 0.762)
			(stroke
				(width 0.1524)
				(type default)
			)
			(layer "B.SilkS")
		)
		(fp_line
			(start 1.524 -0.762)
			(end -1.524 -0.762)
			(stroke
				(width 0.1524)
				(type default)
			)
			(layer "B.SilkS")
		)
		(fp_line
			(start 1.524 0.762)
			(end 1.524 -0.762)
			(stroke
				(width 0.1524)
				(type default)
			)
			(layer "B.SilkS")
		)
		(fp_line
			(start -1.1049 -0.724916)
			(end 1.1049 -0.724916)
			(stroke
				(width 0.1)
				(type default)
			)
			(layer "B.Fab")
		)
		(fp_line
			(start -1.1049 0.724916)
			(end -1.1049 -0.724916)
			(stroke
				(width 0.1)
				(type default)
			)
			(layer "B.Fab")
		)
		(fp_line
			(start 1.1049 -0.724916)
			(end 1.1049 0.724916)
			(stroke
				(width 0.1)
				(type default)
			)
			(layer "B.Fab")
		)
		(fp_line
			(start 1.1049 0.724916)
			(end -1.1049 0.724916)
			(stroke
				(width 0.1)
				(type default)
			)
			(layer "B.Fab")
		)
		(pad "1" smd rect
			(at 0.889 0)
			(size 1.016 1.27)
			(layers "B.Cu" "B.Mask" "B.Paste")
			(net "P12V_MEM_CPU0")
		)
		(pad "2" smd rect
			(at -0.889 0)
			(size 1.016 1.27)
			(layers "B.Cu" "B.Mask" "B.Paste")
			(net "GND")
		)
	)
)
